FILE_TYPE=LIBRARY_PARTS ;
PRIMITIVE 'RES','RES_0402LF';
 PIN
  'A':
   PIN_GROUP='1';
   PIN_NUMBER='(1)';
   PIN_TYPE='UNSPEC';
  'B':
   PIN_GROUP='1';
   PIN_NUMBER='(2)';
   PIN_TYPE='UNSPEC';
 END_PIN;
 BODY
  PART_NAME='RES';
  PHYS_DES_PREFIX='R';
 END_BODY;
END_PRIMITIVE;
END.
